# TIMECARD (Time Appliance Project (Time Card)) — schematic netlist excerpt (pin names and nets, part order shuffled) for the footprints in the layout excerpt that follows; sources: Cadence DE-HDL packaged netlist, KiCad conversion of R4006-B0001-02_R01.brd

R271  RESISTOR  4.7KOHM 1%  pkg SMC_0402R_H016  page 11 : \1\ = SG ; \2\ = FPGA_IN_GPSTP2_OUT
R160  RESISTOR  4.7KOHM 1%  pkg SMC_0402R_H016  page 16 : \1\ = XP3R3V_FPGA ; \2\ = UNNAMED_5_24LC16BTISTTSSOP8_I_1

(kicad_pcb
	(version 20260206)
	(generator "pcbnew")
	(generator_version "10.0")
	(general
		(thickness 1.6)
		(legacy_teardrops no)
	)
	(paper "A4")
	(title_block
		(title "timecard-production-celestica-r4006 — R4006-B0001-02_R01.brd")
		(comment 1 "Time Appliance Project (Time Card) / footprints 877-878 of 1113")
	)
	(layers
		(0 "F.Cu" signal "TOP")
		(4 "In1.Cu" signal "L02_GND1")
		(6 "In2.Cu" signal "L03_SIG1")
		(8 "In3.Cu" signal "L04_GND2")
		(10 "In4.Cu" signal "L05_VCC1")
		(12 "In5.Cu" signal "L06_VCC2")
		(14 "In6.Cu" signal "L07_GND3")
		(16 "In7.Cu" signal "L08_SIG2")
		(18 "In8.Cu" signal "L09_GND4")
		(2 "B.Cu" signal "BOTTOM")
		(9 "F.Adhes" user "F.Adhesive")
		(11 "B.Adhes" user "B.Adhesive")
		(13 "F.Paste" user "Package Geometry/Pastemask Top")
		(15 "B.Paste" user "Package Geometry/Pastemask Bottom")
		(5 "F.SilkS" user "Ref Des/Silkscreen Top")
		(7 "B.SilkS" user "Ref Des/Silkscreen Bottom")
		(1 "F.Mask" user "Board Geometry/Soldermask Top")
		(3 "B.Mask" user "Board Geometry/Soldermask Bottom")
		(17 "Dwgs.User" user "User.Drawings")
		(19 "Cmts.User" user "User.Comments")
		(21 "Eco1.User" user "User.Eco1")
		(23 "Eco2.User" user "User.Eco2")
		(25 "Edge.Cuts" user "Board Geometry/Outline")
		(27 "Margin" user)
		(31 "F.CrtYd" user "Package Geometry/Place Bound Top")
		(29 "B.CrtYd" user "Package Geometry/Place Bound Bottom")
		(35 "F.Fab" user "Ref Des/Assembly Top")
		(33 "B.Fab" user "Ref Des/Assembly Bottom")
	)
	(footprint ""
		(layer "B.Cu")
		(at 20.0152 -23.6728 -90)
		(property "Reference" "R160"
			(at -3.8862 -0.26543 270)
			(unlocked yes)
			(layer "B.SilkS")
			(effects
				(font
					(size 0.7874 0.5842)
					(thickness 0.1524)
				)
				(justify mirror)
			)
		)
		(property "Value" "VAL*"
			(at -0.02032 2.13233 270)
			(unlocked yes)
			(layer "B.Fab")
			(hide yes)
			(effects
				(font
					(size 0.7874 0.5842)
					(thickness 0.1524)
				)
				(justify mirror)
			)
		)
		(property "Tolerance" "TOL*"
			(at -0.044704 3.05435 270)
			(unlocked yes)
			(layer "Cmts.User")
			(hide yes)
			(effects
				(font
					(size 0.7874 0.5842)
					(thickness 0.1524)
				)
				(justify mirror)
			)
		)
		(property "User Part Number" "PARTNUM*"
			(at -0.02032 4.024884 270)
			(unlocked yes)
			(layer "Cmts.User")
			(hide yes)
			(effects
				(font
					(size 0.7874 0.5842)
					(thickness 0.1524)
				)
				(justify mirror)
			)
		)
		(property "Device Type" "RESISTOR-G155-14701-01,4.7KOHMA"
			(at -0.008382 1.210564 270)
			(unlocked yes)
			(layer "B.Fab")
			(hide yes)
			(effects
				(font
					(size 0.7874 0.5842)
					(thickness 0.1524)
				)
				(justify mirror)
			)
		)
		(duplicate_pad_numbers_are_jumpers no)
		(fp_line
			(start -1.143 0.5588)
			(end -1.143 -0.5588)
			(stroke
				(width 0.1)
				(type default)
			)
			(layer "B.SilkS")
		)
		(fp_line
			(start 1.143 0.5588)
			(end -1.143 0.5588)
			(stroke
				(width 0.1)
				(type default)
			)
			(layer "B.SilkS")
		)
		(fp_line
			(start -1.143 -0.5588)
			(end 1.143 -0.5588)
			(stroke
				(width 0.1)
				(type default)
			)
			(layer "B.SilkS")
		)
		(fp_line
			(start 1.143 -0.5588)
			(end 1.143 0.5588)
			(stroke
				(width 0.1)
				(type default)
			)
			(layer "B.SilkS")
		)
		(fp_rect
			(start 1.143 -0.5588)
			(end -1.143 0.5588)
			(stroke
				(width 0)
				(type default)
			)
			(fill no)
			(layer "B.CrtYd")
		)
		(fp_line
			(start -0.508 0.3048)
			(end -0.508 -0.3048)
			(stroke
				(width 0.1)
				(type default)
			)
			(layer "B.Fab")
		)
		(fp_line
			(start 0.508 0.3048)
			(end -0.508 0.3048)
			(stroke
				(width 0.1)
				(type default)
			)
			(layer "B.Fab")
		)
		(fp_line
			(start -0.508 -0.3048)
			(end 0.508 -0.3048)
			(stroke
				(width 0.1)
				(type default)
			)
			(layer "B.Fab")
		)
		(fp_line
			(start 0.508 -0.3048)
			(end 0.508 0.3048)
			(stroke
				(width 0.1)
				(type default)
			)
			(layer "B.Fab")
		)
		(pad "1" smd rect
			(at 0.5334 0 90)
			(size 0.7112 0.6096)
			(layers "B.Cu" "B.Mask" "B.Paste")
			(net "XP3R3V_FPGA")
		)
		(pad "2" smd rect
			(at -0.5334 0 90)
			(size 0.7112 0.6096)
			(layers "B.Cu" "B.Mask" "B.Paste")
			(net "UNNAMED_5_24LC16BTISTTSSOP8_I_1")
		)
		(zone
			(layer "B.Cu")
			(hatch none 0.5)
			(connect_pads
				(clearance 0)
			)
			(min_thickness 0.25)
			(keepout
				(tracks allowed)
				(vias not_allowed)
				(pads allowed)
				(copperpour not_allowed)
				(footprints allowed)
			)
			(placement
				(enabled no)
				(sheetname "")
			)
			(fill
				(thermal_gap 0.5)
				(thermal_bridge_width 0.5)
				(island_removal_mode 0)
			)
			(polygon
				(pts
					(xy 20.32 -23.5966) (xy 20.32 -23.749) (xy 19.7104 -23.749) (xy 19.7104 -23.5966)
				)
			)
		)
	)
	(footprint ""
		(layer "B.Cu")
		(at 118.847108 -47.323248 -90)
		(property "Reference" "R271"
			(at -1.698752 -1.771142 270)
			(unlocked yes)
			(layer "B.SilkS")
			(effects
				(font
					(size 0.635 0.4064)
					(thickness 0.1524)
				)
				(justify mirror)
			)
		)
		(property "Value" "VAL*"
			(at 0 3.718306 270)
			(unlocked yes)
			(layer "B.Fab")
			(hide yes)
			(effects
				(font
					(size 0.7874 0.5842)
					(thickness 0.127)
				)
				(justify mirror)
			)
		)
		(property "Tolerance" "TOL*"
			(at 0 4.861306 270)
			(unlocked yes)
			(layer "Cmts.User")
			(hide yes)
			(effects
				(font
					(size 0.7874 0.5842)
					(thickness 0.127)
				)
				(justify mirror)
			)
		)
		(property "User Part Number" "PARTNUM*"
			(at 0 2.575306 270)
			(unlocked yes)
			(layer "Cmts.User")
			(hide yes)
			(effects
				(font
					(size 0.7874 0.5842)
					(thickness 0.127)
				)
				(justify mirror)
			)
		)
		(property "Device Type" "RESISTOR-G155-14701-01,4.7KOHMA"
			(at 0 1.432306 270)
			(unlocked yes)
			(layer "B.Fab")
			(hide yes)
			(effects
				(font
					(size 0.7874 0.5842)
					(thickness 0.127)
				)
				(justify mirror)
			)
		)
		(duplicate_pad_numbers_are_jumpers no)
		(fp_line
			(start -0.970026 0.4699)
			(end 0.970026 0.4699)
			(stroke
				(width 0.1)
				(type default)
			)
			(layer "B.SilkS")
		)
		(fp_line
			(start 0.970026 0.4699)
			(end 0.970026 -0.4699)
			(stroke
				(width 0.1)
				(type default)
			)
			(layer "B.SilkS")
		)
		(fp_line
			(start -0.970026 -0.4699)
			(end -0.970026 0.4699)
			(stroke
				(width 0.1)
				(type default)
			)
			(layer "B.SilkS")
		)
		(fp_line
			(start 0.970026 -0.4699)
			(end -0.970026 -0.4699)
			(stroke
				(width 0.1)
				(type default)
			)
			(layer "B.SilkS")
		)
		(fp_poly
			(pts
				(xy 0.970026 0.4699) (xy -0.970026 0.4699) (xy -0.970026 -0.4699) (xy 0.970026 -0.4699)
			)
			(stroke
				(width 0)
				(type default)
			)
			(fill no)
			(layer "B.CrtYd")
		)
		(fp_line
			(start -0.508 0.3048)
			(end 0.508 0.3048)
			(stroke
				(width 0.1)
				(type default)
			)
			(layer "B.Fab")
		)
		(fp_line
			(start 0.508 0.3048)
			(end 0.508 -0.3048)
			(stroke
				(width 0.1)
				(type default)
			)
			(layer "B.Fab")
		)
		(fp_line
			(start -0.508 -0.3048)
			(end -0.508 0.3048)
			(stroke
				(width 0.1)
				(type default)
			)
			(layer "B.Fab")
		)
		(fp_line
			(start 0.508 -0.3048)
			(end -0.508 -0.3048)
			(stroke
				(width 0.1)
				(type default)
			)
			(layer "B.Fab")
		)
		(pad "1" smd circle
			(at 0.500126 0 90)
			(size 0.635 0.635)
			(layers "B.Cu" "B.Mask" "B.Paste")
			(net "SG")
		)
		(pad "2" smd circle
			(at -0.500126 0 90)
			(size 0.635 0.635)
			(layers "B.Cu" "B.Mask" "B.Paste")
			(net "FPGA_IN_GPSTP2_OUT")
		)
	)
)
